(kicad_pcb
	(version 20260206)
	(generator "pcbnew")
	(generator_version "10.0")
	(general
		(thickness 1.6)
		(legacy_teardrops no)
	)
	(paper "A4")
	(title_block
		(title "Bryce Canyon_IOM_M2_16342-2_OCP.brd")
		(comment 1 "Bryce Canyon / footprints 888-894 of 1146")
	)
	(layers
		(0 "F.Cu" signal "TOP")
		(4 "In1.Cu" signal "L2GND")
		(6 "In2.Cu" signal "L3")
		(8 "In3.Cu" signal "L4VCC")
		(10 "In4.Cu" signal "L5VCC")
		(12 "In5.Cu" signal "L6")
		(14 "In6.Cu" signal "L7GND")
		(2 "B.Cu" signal "BOTTOM")
		(9 "F.Adhes" user "F.Adhesive")
		(11 "B.Adhes" user "B.Adhesive")
		(13 "F.Paste" user "Package Geometry/Pastemask Top")
		(15 "B.Paste" user "Package Geometry/Pastemask Bottom")
		(5 "F.SilkS" user "Ref Des/Silkscreen Top")
		(7 "B.SilkS" user "Ref Des/Silkscreen Bottom")
		(1 "F.Mask" user "Board Geometry/Soldermask Top")
		(3 "B.Mask" user "Board Geometry/Soldermask Bottom")
		(17 "Dwgs.User" user "User.Drawings")
		(19 "Cmts.User" user "User.Comments")
		(21 "Eco1.User" user "User.Eco1")
		(23 "Eco2.User" user "User.Eco2")
		(25 "Edge.Cuts" user "Board Geometry/Outline")
		(27 "Margin" user)
		(31 "F.CrtYd" user "Package Geometry/Place Bound Top")
		(29 "B.CrtYd" user "Package Geometry/Place Bound Bottom")
		(35 "F.Fab" user "Ref Des/Assembly Top")
		(33 "B.Fab" user "Ref Des/Assembly Bottom")
	)
	(footprint ""
		(layer "B.Cu")
		(at 61.26988 -142.880334 90)
		(property "Reference" "R151"
			(at 0 0 90)
			(layer "B.SilkS")
			(hide yes)
			(effects
				(font
					(size 1.27 1.27)
				)
				(justify mirror)
			)
		)
		(property "Value" "0R2J-2-GP"
			(at -0.064008 -3.993896 90)
			(unlocked yes)
			(layer "B.Fab")
			(hide yes)
			(effects
				(font
					(size 1.016 1.016)
					(thickness 0.1524)
				)
				(justify mirror)
			)
		)
		(property "Device Type" "R402H16"
			(at -0.064008 -5.517896 90)
			(unlocked yes)
			(layer "B.Fab")
			(hide yes)
			(effects
				(font
					(size 1.016 1.016)
					(thickness 0.1524)
				)
				(justify mirror)
			)
		)
		(duplicate_pad_numbers_are_jumpers no)
		(fp_line
			(start 0.508 -0.9398)
			(end 0.508 0.9398)
			(stroke
				(width 0.1524)
				(type default)
			)
			(layer "B.SilkS")
		)
		(fp_line
			(start -0.508 -0.9398)
			(end 0.508 -0.9398)
			(stroke
				(width 0.1524)
				(type default)
			)
			(layer "B.SilkS")
		)
		(fp_rect
			(start 0.508 0.9398)
			(end -0.508 -0.9398)
			(stroke
				(width 0)
				(type default)
			)
			(fill no)
			(layer "B.CrtYd")
		)
		(fp_rect
			(start 0.508 0.9398)
			(end -0.508 -0.9398)
			(stroke
				(width 0)
				(type default)
			)
			(fill no)
			(layer "B.Fab")
		)
		(pad "1" smd custom
			(at 0 -0.4445 270)
			(size 0.1397 0.1397)
			(layers "B.Cu" "B.Mask" "B.Paste")
			(net "BMC_SMB10_CLK")
			(options
				(clearance outline)
				(anchor circle)
			)
			(primitives
				(gr_poly
					(pts
						(arc
							(start -0.1778 0.2794)
							(mid -0.249642 0.249642)
							(end -0.2794 0.1778)
						)
						(arc
							(start -0.2794 -0.1778)
							(mid -0.249642 -0.249642)
							(end -0.1778 -0.2794)
						)
						(arc
							(start 0.1778 -0.2794)
							(mid 0.249642 -0.249642)
							(end 0.2794 -0.1778)
						)
						(arc
							(start 0.2794 0.1778)
							(mid 0.249642 0.249642)
							(end 0.1778 0.2794)
						)
					)
					(width 0)
					(fill yes)
				)
			)
		)
		(pad "2" smd custom
			(at 0 0.4445 270)
			(size 0.1397 0.1397)
			(layers "B.Cu" "B.Mask" "B.Paste")
			(net "I2C_EXP_LOC_SCL_OUT")
			(options
				(clearance outline)
				(anchor circle)
			)
			(primitives
				(gr_poly
					(pts
						(arc
							(start -0.1778 0.2794)
							(mid -0.249642 0.249642)
							(end -0.2794 0.1778)
						)
						(arc
							(start -0.2794 -0.1778)
							(mid -0.249642 -0.249642)
							(end -0.1778 -0.2794)
						)
						(arc
							(start 0.1778 -0.2794)
							(mid 0.249642 -0.249642)
							(end 0.2794 -0.1778)
						)
						(arc
							(start 0.2794 0.1778)
							(mid 0.249642 0.249642)
							(end 0.1778 0.2794)
						)
					)
					(width 0)
					(fill yes)
				)
			)
		)
	)
	(footprint ""
		(layer "B.Cu")
		(at 25.89022 -146.418808 90)
		(property "Reference" "C73"
			(at 0 0 90)
			(layer "B.SilkS")
			(hide yes)
			(effects
				(font
					(size 1.27 1.27)
				)
				(justify mirror)
			)
		)
		(property "Value" "SCD1U16V2KX-3GP"
			(at -1.1811 -2.7051 90)
			(unlocked yes)
			(layer "B.Fab")
			(hide yes)
			(effects
				(font
					(size 1.016 1.016)
					(thickness 0.1524)
				)
				(justify mirror)
			)
		)
		(property "Device Type" "C402H22"
			(at -1.1811 -4.2291 90)
			(unlocked yes)
			(layer "B.Fab")
			(hide yes)
			(effects
				(font
					(size 1.016 1.016)
					(thickness 0.1524)
				)
				(justify mirror)
			)
		)
		(duplicate_pad_numbers_are_jumpers no)
		(fp_rect
			(start 0.4318 0.9525)
			(end -0.4318 -0.9525)
			(stroke
				(width 0)
				(type default)
			)
			(fill no)
			(layer "B.CrtYd")
		)
		(fp_rect
			(start 0.4318 0.9525)
			(end -0.4318 -0.9525)
			(stroke
				(width 0)
				(type default)
			)
			(fill no)
			(layer "B.Fab")
		)
		(pad "1" smd custom
			(at 0 -0.4445 270)
			(size 0.1524 0.1524)
			(layers "B.Cu" "B.Mask" "B.Paste")
			(net "GND")
			(options
				(clearance outline)
				(anchor circle)
			)
			(primitives
				(gr_poly
					(pts
						(arc
							(start 0.3048 0.2032)
							(mid 0.275042 0.275042)
							(end 0.2032 0.3048)
						)
						(arc
							(start -0.2032 0.3048)
							(mid -0.275042 0.275042)
							(end -0.3048 0.2032)
						)
						(arc
							(start -0.3048 -0.2032)
							(mid -0.275042 -0.275042)
							(end -0.2032 -0.3048)
						)
						(arc
							(start 0.2032 -0.3048)
							(mid 0.275042 -0.275042)
							(end 0.3048 -0.2032)
						)
					)
					(width 0)
					(fill yes)
				)
			)
		)
		(pad "2" smd custom
			(at 0 0.4445 270)
			(size 0.1524 0.1524)
			(layers "B.Cu" "B.Mask" "B.Paste")
			(net "P1V2_STBY")
			(options
				(clearance outline)
				(anchor circle)
			)
			(primitives
				(gr_poly
					(pts
						(arc
							(start 0.3048 0.2032)
							(mid 0.275042 0.275042)
							(end 0.2032 0.3048)
						)
						(arc
							(start -0.2032 0.3048)
							(mid -0.275042 0.275042)
							(end -0.3048 0.2032)
						)
						(arc
							(start -0.3048 -0.2032)
							(mid -0.275042 -0.275042)
							(end -0.2032 -0.3048)
						)
						(arc
							(start 0.2032 -0.3048)
							(mid 0.275042 -0.275042)
							(end 0.3048 -0.2032)
						)
					)
					(width 0)
					(fill yes)
				)
			)
		)
	)
	(footprint ""
		(layer "B.Cu")
		(at 37.592 -120.3452 180)
		(property "Reference" "R91"
			(at 0 0 0)
			(layer "B.SilkS")
			(hide yes)
			(effects
				(font
					(size 1.27 1.27)
				)
				(justify mirror)
			)
		)
		(property "Value" "300R2F-GP"
			(at -0.064008 -3.993896 180)
			(unlocked yes)
			(layer "B.Fab")
			(hide yes)
			(effects
				(font
					(size 1.016 1.016)
					(thickness 0.1524)
				)
				(justify mirror)
			)
		)
		(property "Device Type" "R402H16"
			(at -0.064008 -5.517896 180)
			(unlocked yes)
			(layer "B.Fab")
			(hide yes)
			(effects
				(font
					(size 1.016 1.016)
					(thickness 0.1524)
				)
				(justify mirror)
			)
		)
		(duplicate_pad_numbers_are_jumpers no)
		(fp_line
			(start 0.508 -0.9398)
			(end 0.508 0.9398)
			(stroke
				(width 0.1524)
				(type default)
			)
			(layer "B.SilkS")
		)
		(fp_line
			(start -0.508 -0.9398)
			(end 0.508 -0.9398)
			(stroke
				(width 0.1524)
				(type default)
			)
			(layer "B.SilkS")
		)
		(fp_rect
			(start 0.508 0.9398)
			(end -0.508 -0.9398)
			(stroke
				(width 0)
				(type default)
			)
			(fill no)
			(layer "B.CrtYd")
		)
		(fp_rect
			(start 0.508 0.9398)
			(end -0.508 -0.9398)
			(stroke
				(width 0)
				(type default)
			)
			(fill no)
			(layer "B.Fab")
		)
		(pad "1" smd custom
			(at 0 -0.4445)
			(size 0.1397 0.1397)
			(layers "B.Cu" "B.Mask" "B.Paste")
			(net "GND")
			(options
				(clearance outline)
				(anchor circle)
			)
			(primitives
				(gr_poly
					(pts
						(arc
							(start -0.1778 0.2794)
							(mid -0.249642 0.249642)
							(end -0.2794 0.1778)
						)
						(arc
							(start -0.2794 -0.1778)
							(mid -0.249642 -0.249642)
							(end -0.1778 -0.2794)
						)
						(arc
							(start 0.1778 -0.2794)
							(mid 0.249642 -0.249642)
							(end 0.2794 -0.1778)
						)
						(arc
							(start 0.2794 0.1778)
							(mid 0.249642 0.249642)
							(end 0.1778 0.2794)
						)
					)
					(width 0)
					(fill yes)
				)
			)
		)
		(pad "2" smd custom
			(at 0 0.4445)
			(size 0.1397 0.1397)
			(layers "B.Cu" "B.Mask" "B.Paste")
			(net "BMC_CPU_DIS")
			(options
				(clearance outline)
				(anchor circle)
			)
			(primitives
				(gr_poly
					(pts
						(arc
							(start -0.1778 0.2794)
							(mid -0.249642 0.249642)
							(end -0.2794 0.1778)
						)
						(arc
							(start -0.2794 -0.1778)
							(mid -0.249642 -0.249642)
							(end -0.1778 -0.2794)
						)
						(arc
							(start 0.1778 -0.2794)
							(mid 0.249642 -0.249642)
							(end 0.2794 -0.1778)
						)
						(arc
							(start 0.2794 0.1778)
							(mid 0.249642 0.249642)
							(end 0.1778 0.2794)
						)
					)
					(width 0)
					(fill yes)
				)
			)
		)
	)
	(footprint ""
		(layer "B.Cu")
		(at 198.797418 -130.391408 180)
		(property "Reference" "C609"
			(at 0 0 0)
			(layer "B.SilkS")
			(hide yes)
			(effects
				(font
					(size 1.27 1.27)
				)
				(justify mirror)
			)
		)
		(property "Value" "SCD1U16V2KX-3GP"
			(at -1.1811 -2.7051 180)
			(unlocked yes)
			(layer "B.Fab")
			(hide yes)
			(effects
				(font
					(size 1.016 1.016)
					(thickness 0.1524)
				)
				(justify mirror)
			)
		)
		(property "Device Type" "C402H22"
			(at -1.1811 -4.2291 180)
			(unlocked yes)
			(layer "B.Fab")
			(hide yes)
			(effects
				(font
					(size 1.016 1.016)
					(thickness 0.1524)
				)
				(justify mirror)
			)
		)
		(duplicate_pad_numbers_are_jumpers no)
		(fp_rect
			(start 0.4318 0.9525)
			(end -0.4318 -0.9525)
			(stroke
				(width 0)
				(type default)
			)
			(fill no)
			(layer "B.CrtYd")
		)
		(fp_rect
			(start 0.4318 0.9525)
			(end -0.4318 -0.9525)
			(stroke
				(width 0)
				(type default)
			)
			(fill no)
			(layer "B.Fab")
		)
		(pad "1" smd custom
			(at 0 -0.4445)
			(size 0.1524 0.1524)
			(layers "B.Cu" "B.Mask" "B.Paste")
			(net "P3V3_M2")
			(options
				(clearance outline)
				(anchor circle)
			)
			(primitives
				(gr_poly
					(pts
						(arc
							(start 0.3048 0.2032)
							(mid 0.275042 0.275042)
							(end 0.2032 0.3048)
						)
						(arc
							(start -0.2032 0.3048)
							(mid -0.275042 0.275042)
							(end -0.3048 0.2032)
						)
						(arc
							(start -0.3048 -0.2032)
							(mid -0.275042 -0.275042)
							(end -0.2032 -0.3048)
						)
						(arc
							(start 0.2032 -0.3048)
							(mid 0.275042 -0.275042)
							(end 0.3048 -0.2032)
						)
					)
					(width 0)
					(fill yes)
				)
			)
		)
		(pad "2" smd custom
			(at 0 0.4445)
			(size 0.1524 0.1524)
			(layers "B.Cu" "B.Mask" "B.Paste")
			(net "GND")
			(options
				(clearance outline)
				(anchor circle)
			)
			(primitives
				(gr_poly
					(pts
						(arc
							(start 0.3048 0.2032)
							(mid 0.275042 0.275042)
							(end 0.2032 0.3048)
						)
						(arc
							(start -0.2032 0.3048)
							(mid -0.275042 0.275042)
							(end -0.3048 0.2032)
						)
						(arc
							(start -0.3048 -0.2032)
							(mid -0.275042 -0.275042)
							(end -0.2032 -0.3048)
						)
						(arc
							(start 0.2032 -0.3048)
							(mid 0.275042 -0.275042)
							(end 0.3048 -0.2032)
						)
					)
					(width 0)
					(fill yes)
				)
			)
		)
	)
	(footprint ""
		(layer "B.Cu")
		(at 69.547486 -142.776194 180)
		(property "Reference" "R193"
			(at 0 0 0)
			(layer "B.SilkS")
			(hide yes)
			(effects
				(font
					(size 1.27 1.27)
				)
				(justify mirror)
			)
		)
		(property "Value" "20KR2F-L-GP"
			(at -0.064008 -3.993896 180)
			(unlocked yes)
			(layer "B.Fab")
			(hide yes)
			(effects
				(font
					(size 1.016 1.016)
					(thickness 0.1524)
				)
				(justify mirror)
			)
		)
		(property "Device Type" "R402H16"
			(at -0.064008 -5.517896 180)
			(unlocked yes)
			(layer "B.Fab")
			(hide yes)
			(effects
				(font
					(size 1.016 1.016)
					(thickness 0.1524)
				)
				(justify mirror)
			)
		)
		(duplicate_pad_numbers_are_jumpers no)
		(fp_line
			(start 0.508 -0.9398)
			(end 0.508 0.9398)
			(stroke
				(width 0.1524)
				(type default)
			)
			(layer "B.SilkS")
		)
		(fp_line
			(start -0.508 -0.9398)
			(end 0.508 -0.9398)
			(stroke
				(width 0.1524)
				(type default)
			)
			(layer "B.SilkS")
		)
		(fp_rect
			(start 0.508 0.9398)
			(end -0.508 -0.9398)
			(stroke
				(width 0)
				(type default)
			)
			(fill no)
			(layer "B.CrtYd")
		)
		(fp_rect
			(start 0.508 0.9398)
			(end -0.508 -0.9398)
			(stroke
				(width 0)
				(type default)
			)
			(fill no)
			(layer "B.Fab")
		)
		(pad "1" smd custom
			(at 0 -0.4445)
			(size 0.1397 0.1397)
			(layers "B.Cu" "B.Mask" "B.Paste")
			(net "P3V3_STBY")
			(options
				(clearance outline)
				(anchor circle)
			)
			(primitives
				(gr_poly
					(pts
						(arc
							(start -0.1778 0.2794)
							(mid -0.249642 0.249642)
							(end -0.2794 0.1778)
						)
						(arc
							(start -0.2794 -0.1778)
							(mid -0.249642 -0.249642)
							(end -0.1778 -0.2794)
						)
						(arc
							(start 0.1778 -0.2794)
							(mid 0.249642 -0.249642)
							(end 0.2794 -0.1778)
						)
						(arc
							(start 0.2794 0.1778)
							(mid 0.249642 0.249642)
							(end 0.1778 0.2794)
						)
					)
					(width 0)
					(fill yes)
				)
			)
		)
		(pad "2" smd custom
			(at 0 0.4445)
			(size 0.1397 0.1397)
			(layers "B.Cu" "B.Mask" "B.Paste")
			(net "I2C_DEBUG_SCL_L")
			(options
				(clearance outline)
				(anchor circle)
			)
			(primitives
				(gr_poly
					(pts
						(arc
							(start -0.1778 0.2794)
							(mid -0.249642 0.249642)
							(end -0.2794 0.1778)
						)
						(arc
							(start -0.2794 -0.1778)
							(mid -0.249642 -0.249642)
							(end -0.1778 -0.2794)
						)
						(arc
							(start 0.1778 -0.2794)
							(mid 0.249642 -0.249642)
							(end 0.2794 -0.1778)
						)
						(arc
							(start 0.2794 0.1778)
							(mid 0.249642 0.249642)
							(end 0.1778 0.2794)
						)
					)
					(width 0)
					(fill yes)
				)
			)
		)
	)
	(footprint ""
		(layer "B.Cu")
		(at 38.1 -149.987 90)
		(property "Reference" "R740"
			(at 0 0 90)
			(layer "B.SilkS")
			(hide yes)
			(effects
				(font
					(size 1.27 1.27)
				)
				(justify mirror)
			)
		)
		(property "Value" "4K7R2F-GP"
			(at -0.064008 -3.993896 90)
			(unlocked yes)
			(layer "B.Fab")
			(hide yes)
			(effects
				(font
					(size 1.016 1.016)
					(thickness 0.1524)
				)
				(justify mirror)
			)
		)
		(property "Device Type" "R402H16"
			(at -0.064008 -5.517896 90)
			(unlocked yes)
			(layer "B.Fab")
			(hide yes)
			(effects
				(font
					(size 1.016 1.016)
					(thickness 0.1524)
				)
				(justify mirror)
			)
		)
		(duplicate_pad_numbers_are_jumpers no)
		(fp_line
			(start 0.508 -0.9398)
			(end 0.508 0.9398)
			(stroke
				(width 0.1524)
				(type default)
			)
			(layer "B.SilkS")
		)
		(fp_line
			(start -0.508 -0.9398)
			(end 0.508 -0.9398)
			(stroke
				(width 0.1524)
				(type default)
			)
			(layer "B.SilkS")
		)
		(fp_rect
			(start 0.508 0.9398)
			(end -0.508 -0.9398)
			(stroke
				(width 0)
				(type default)
			)
			(fill no)
			(layer "B.CrtYd")
		)
		(fp_rect
			(start 0.508 0.9398)
			(end -0.508 -0.9398)
			(stroke
				(width 0)
				(type default)
			)
			(fill no)
			(layer "B.Fab")
		)
		(pad "1" smd custom
			(at 0 -0.4445 270)
			(size 0.1397 0.1397)
			(layers "B.Cu" "B.Mask" "B.Paste")
			(net "GND")
			(options
				(clearance outline)
				(anchor circle)
			)
			(primitives
				(gr_poly
					(pts
						(arc
							(start -0.1778 0.2794)
							(mid -0.249642 0.249642)
							(end -0.2794 0.1778)
						)
						(arc
							(start -0.2794 -0.1778)
							(mid -0.249642 -0.249642)
							(end -0.1778 -0.2794)
						)
						(arc
							(start 0.1778 -0.2794)
							(mid 0.249642 -0.249642)
							(end 0.2794 -0.1778)
						)
						(arc
							(start 0.2794 0.1778)
							(mid 0.249642 0.249642)
							(end 0.1778 0.2794)
						)
					)
					(width 0)
					(fill yes)
				)
			)
		)
		(pad "2" smd custom
			(at 0 0.4445 270)
			(size 0.1397 0.1397)
			(layers "B.Cu" "B.Mask" "B.Paste")
			(net "IOM_TYPE0")
			(options
				(clearance outline)
				(anchor circle)
			)
			(primitives
				(gr_poly
					(pts
						(arc
							(start -0.1778 0.2794)
							(mid -0.249642 0.249642)
							(end -0.2794 0.1778)
						)
						(arc
							(start -0.2794 -0.1778)
							(mid -0.249642 -0.249642)
							(end -0.1778 -0.2794)
						)
						(arc
							(start 0.1778 -0.2794)
							(mid 0.249642 -0.249642)
							(end 0.2794 -0.1778)
						)
						(arc
							(start 0.2794 0.1778)
							(mid 0.249642 0.249642)
							(end 0.1778 0.2794)
						)
					)
					(width 0)
					(fill yes)
				)
			)
		)
	)
	(footprint ""
		(layer "B.Cu")
		(at 77.137768 -147.114006 -90)
		(property "Reference" "U45"
			(at 0 0 90)
			(layer "B.SilkS")
			(hide yes)
			(effects
				(font
					(size 1.27 1.27)
				)
				(justify mirror)
			)
		)
		(property "Value" "PCA9306DCTT-GP"
			(at 0 -11.6332 270)
			(unlocked yes)
			(layer "B.Fab")
			(hide yes)
			(effects
				(font
					(size 1.016 1.016)
					(thickness 0.1524)
				)
				(justify mirror)
			)
		)
		(property "Device Type" "SSOIC8H52"
			(at 0 -13.1572 270)
			(unlocked yes)
			(layer "B.Fab")
			(hide yes)
			(effects
				(font
					(size 1.016 1.016)
					(thickness 0.1524)
				)
				(justify mirror)
			)
		)
		(duplicate_pad_numbers_are_jumpers no)
		(fp_line
			(start -1.0668 0.5842)
			(end 1.524 0.5842)
			(stroke
				(width 0.1524)
				(type default)
			)
			(layer "B.SilkS")
		)
		(fp_line
			(start 1.524 0.5842)
			(end 1.524 2.286)
			(stroke
				(width 0.508)
				(type default)
			)
			(layer "B.SilkS")
		)
		(fp_line
			(start 1.397 0)
			(end 1.7018 0.3048)
			(stroke
				(width 0.1524)
				(type default)
			)
			(layer "B.SilkS")
		)
		(fp_line
			(start 1.397 0)
			(end 1.7018 -0.3048)
			(stroke
				(width 0.1524)
				(type default)
			)
			(layer "B.SilkS")
		)
		(fp_line
			(start -1.0668 -0.5842)
			(end -1.0668 0.5842)
			(stroke
				(width 0.1524)
				(type default)
			)
			(layer "B.SilkS")
		)
		(fp_line
			(start 1.7018 -0.5842)
			(end 1.7018 2.286)
			(stroke
				(width 0.1524)
				(type default)
			)
			(layer "B.SilkS")
		)
		(fp_line
			(start 1.7018 -0.5842)
			(end -1.0668 -0.5842)
			(stroke
				(width 0.1524)
				(type default)
			)
			(layer "B.SilkS")
		)
		(fp_poly
			(pts
				(xy 1.1684 -0.5842) (xy -1.0668 -0.5842) (xy -1.0668 0.5842) (xy 1.1684 0.5842)
			)
			(stroke
				(width 0)
				(type default)
			)
			(fill yes)
			(layer "B.SilkS")
		)
		(fp_poly
			(pts
				(xy 1.778 2.54) (xy -1.778 2.54) (xy -1.778 -2.54) (xy 1.778 -2.54)
			)
			(stroke
				(width 0)
				(type default)
			)
			(fill no)
			(layer "B.CrtYd")
		)
		(fp_poly
			(pts
				(xy 1.778 -2.54) (xy -1.778 -2.54) (xy -1.778 2.54) (xy 1.778 2.54)
			)
			(stroke
				(width 0)
				(type default)
			)
			(fill no)
			(layer "B.Fab")
		)
		(pad "1" smd rect
			(at 0.97536 1.6256 90)
			(size 0.3556 1.524)
			(layers "B.Cu" "B.Mask" "B.Paste")
			(net "GND")
		)
		(pad "2" smd rect
			(at 0.32512 1.6256 90)
			(size 0.3556 1.524)
			(layers "B.Cu" "B.Mask" "B.Paste")
			(net "P3V3_STBY")
		)
		(pad "3" smd rect
			(at -0.32512 1.6256 90)
			(size 0.3556 1.524)
			(layers "B.Cu" "B.Mask" "B.Paste")
			(net "I2C_DEBUG_SCL")
		)
		(pad "4" smd rect
			(at -0.97536 1.6256 90)
			(size 0.3556 1.524)
			(layers "B.Cu" "B.Mask" "B.Paste")
			(net "I2C_DEBUG_SDA")
		)
		(pad "5" smd rect
			(at -0.97536 -1.6256 90)
			(size 0.3556 1.524)
			(layers "B.Cu" "B.Mask" "B.Paste")
			(net "I2C_DEBUG_SDA_L")
		)
		(pad "6" smd rect
			(at -0.32512 -1.6256 90)
			(size 0.3556 1.524)
			(layers "B.Cu" "B.Mask" "B.Paste")
			(net "I2C_DEBUG_SCL_L")
		)
		(pad "7" smd rect
			(at 0.32512 -1.6256 90)
			(size 0.3556 1.524)
			(layers "B.Cu" "B.Mask" "B.Paste")
			(net "P3V3_STBY")
		)
		(pad "8" smd rect
			(at 0.97536 -1.6256 90)
			(size 0.3556 1.524)
			(layers "B.Cu" "B.Mask" "B.Paste")
			(net "DEBUG_CARD_PRSNT")
		)
	)
)
